# SCM (Grand Teton) — schematic netlist excerpt (pin names and nets, part order shuffled) for the footprints in the layout excerpt that follows; sources: Cadence DE-HDL packaged netlist, KiCad conversion of 12092022_DA0F0TMDCD0_F0T_Management_Board_D_brd_V3_OCP.brd

C162  Q_CAP  0.1UF 25V 10% X7R  pkg 0402  page 41 : A = VCCIO4 ; B = GND
C239  Q_CAP  0.1UF 25V 10% EMPTY  pkg 0402  page 29 : A = USB3_FPNL_TXN ; B = USB3_01_TXN_C

(kicad_pcb
	(version 20260206)
	(generator "pcbnew")
	(generator_version "10.0")
	(general
		(thickness 1.6)
		(legacy_teardrops no)
	)
	(paper "A4")
	(title_block
		(title "12092022_DA0F0TMDCD0_F0T_Management_Board_D_brd_V3_OCP.brd")
		(comment 1 "Grand Teton / footprints 741-742 of 1440")
	)
	(layers
		(0 "F.Cu" signal "TOP")
		(4 "In1.Cu" signal "GND")
		(6 "In2.Cu" signal "IN1")
		(8 "In3.Cu" signal "GND1")
		(10 "In4.Cu" signal "IN2")
		(12 "In5.Cu" signal "VCC")
		(14 "In6.Cu" signal "VCC1")
		(16 "In7.Cu" signal "IN3")
		(18 "In8.Cu" signal "GND2")
		(20 "In9.Cu" signal "IN4")
		(22 "In10.Cu" signal "GND3")
		(2 "B.Cu" signal "BOTTOM")
		(9 "F.Adhes" user "F.Adhesive")
		(11 "B.Adhes" user "B.Adhesive")
		(13 "F.Paste" user "Package Geometry/Pastemask Top")
		(15 "B.Paste" user "Package Geometry/Pastemask Bottom")
		(5 "F.SilkS" user "Ref Des/Silkscreen Top")
		(7 "B.SilkS" user "Ref Des/Silkscreen Bottom")
		(1 "F.Mask" user "Board Geometry/Soldermask Top")
		(3 "B.Mask" user "Board Geometry/Soldermask Bottom")
		(17 "Dwgs.User" user "User.Drawings")
		(19 "Cmts.User" user "User.Comments")
		(21 "Eco1.User" user "User.Eco1")
		(23 "Eco2.User" user "User.Eco2")
		(25 "Edge.Cuts" user "Board Geometry/Outline")
		(27 "Margin" user)
		(31 "F.CrtYd" user "Package Geometry/Place Bound Top")
		(29 "B.CrtYd" user "Package Geometry/Place Bound Bottom")
		(35 "F.Fab" user "Ref Des/Assembly Top")
		(33 "B.Fab" user "Ref Des/Assembly Bottom")
	)
	(footprint ""
		(layer "B.Cu")
		(at 45.339 -96.8248 90)
		(property "Reference" "C239"
			(at 0 0 90)
			(layer "B.SilkS")
			(hide yes)
			(effects
				(font
					(size 1.27 1.27)
				)
				(justify mirror)
			)
		)
		(property "Value" ""
			(at 0 0 90)
			(layer "B.Fab")
			(effects
				(font
					(size 1.27 1.27)
				)
				(justify mirror)
			)
		)
		(duplicate_pad_numbers_are_jumpers no)
		(fp_line
			(start 0.7874 -0.4064)
			(end -0.7874 -0.4064)
			(stroke
				(width 0.1524)
				(type default)
			)
			(layer "B.SilkS")
		)
		(fp_line
			(start -0.7874 -0.4064)
			(end -0.7874 0.4064)
			(stroke
				(width 0.1524)
				(type default)
			)
			(layer "B.SilkS")
		)
		(fp_line
			(start 0.7874 0.4064)
			(end 0.7874 -0.4064)
			(stroke
				(width 0.1524)
				(type default)
			)
			(layer "B.SilkS")
		)
		(fp_line
			(start -0.7874 0.4064)
			(end 0.7874 0.4064)
			(stroke
				(width 0.1524)
				(type default)
			)
			(layer "B.SilkS")
		)
		(fp_line
			(start 0.67945 -0.305054)
			(end 0.12065 -0.305054)
			(stroke
				(width 0.1)
				(type default)
			)
			(layer "B.Fab")
		)
		(fp_line
			(start 0.12065 -0.305054)
			(end 0.12065 -0.2794)
			(stroke
				(width 0.1)
				(type default)
			)
			(layer "B.Fab")
		)
		(fp_line
			(start -0.12065 -0.3048)
			(end -0.67945 -0.3048)
			(stroke
				(width 0.1)
				(type default)
			)
			(layer "B.Fab")
		)
		(fp_line
			(start -0.67945 -0.3048)
			(end -0.67945 0.3048)
			(stroke
				(width 0.1)
				(type default)
			)
			(layer "B.Fab")
		)
		(fp_line
			(start 0.12065 -0.2794)
			(end -0.12065 -0.2794)
			(stroke
				(width 0.1)
				(type default)
			)
			(layer "B.Fab")
		)
		(fp_line
			(start -0.12065 -0.2794)
			(end -0.12065 -0.3048)
			(stroke
				(width 0.1)
				(type default)
			)
			(layer "B.Fab")
		)
		(fp_line
			(start 0.12065 0.2794)
			(end 0.12065 0.3048)
			(stroke
				(width 0.1)
				(type default)
			)
			(layer "B.Fab")
		)
		(fp_line
			(start -0.120396 0.2794)
			(end 0.12065 0.2794)
			(stroke
				(width 0.1)
				(type default)
			)
			(layer "B.Fab")
		)
		(fp_line
			(start 0.67945 0.3048)
			(end 0.67945 -0.305054)
			(stroke
				(width 0.1)
				(type default)
			)
			(layer "B.Fab")
		)
		(fp_line
			(start 0.12065 0.3048)
			(end 0.67945 0.3048)
			(stroke
				(width 0.1)
				(type default)
			)
			(layer "B.Fab")
		)
		(fp_line
			(start -0.120396 0.3048)
			(end -0.120396 0.2794)
			(stroke
				(width 0.1)
				(type default)
			)
			(layer "B.Fab")
		)
		(fp_line
			(start -0.67945 0.3048)
			(end -0.120396 0.3048)
			(stroke
				(width 0.1)
				(type default)
			)
			(layer "B.Fab")
		)
		(pad "1" smd circle
			(at 0.40005 0 270)
			(size 0 0)
			(layers "B.Cu" "B.Mask" "B.Paste")
			(net "USB3_FPNL_TXN")
		)
		(pad "2" smd circle
			(at -0.40005 0 270)
			(size 0 0)
			(layers "B.Cu" "B.Mask" "B.Paste")
			(net "USB3_01_TXN_C")
		)
	)
	(footprint ""
		(layer "B.Cu")
		(at 22.653244 -93.606112)
		(property "Reference" "C162"
			(at 0 0 0)
			(layer "B.SilkS")
			(hide yes)
			(effects
				(font
					(size 1.27 1.27)
				)
				(justify mirror)
			)
		)
		(property "Value" ""
			(at 0 0 0)
			(layer "B.Fab")
			(effects
				(font
					(size 1.27 1.27)
				)
				(justify mirror)
			)
		)
		(duplicate_pad_numbers_are_jumpers no)
		(fp_line
			(start -0.69215 -0.2921)
			(end -0.69215 0.2921)
			(stroke
				(width 0.1524)
				(type default)
			)
			(layer "B.SilkS")
		)
		(fp_line
			(start -0.69215 0.2921)
			(end 0.69215 0.2921)
			(stroke
				(width 0.1524)
				(type default)
			)
			(layer "B.SilkS")
		)
		(fp_line
			(start 0.69215 -0.2921)
			(end -0.69215 -0.2921)
			(stroke
				(width 0.1524)
				(type default)
			)
			(layer "B.SilkS")
		)
		(fp_line
			(start 0.69215 0.2921)
			(end 0.69215 -0.2921)
			(stroke
				(width 0.1524)
				(type default)
			)
			(layer "B.SilkS")
		)
		(fp_line
			(start -0.51435 -0.2794)
			(end -0.51435 0.2794)
			(stroke
				(width 0.1)
				(type default)
			)
			(layer "B.Fab")
		)
		(fp_line
			(start -0.51435 0.2794)
			(end 0.51435 0.2794)
			(stroke
				(width 0.1)
				(type default)
			)
			(layer "B.Fab")
		)
		(fp_line
			(start 0.51435 -0.2794)
			(end -0.51435 -0.2794)
			(stroke
				(width 0.1)
				(type default)
			)
			(layer "B.Fab")
		)
		(fp_line
			(start 0.51435 0.2794)
			(end 0.51435 -0.2794)
			(stroke
				(width 0.1)
				(type default)
			)
			(layer "B.Fab")
		)
		(pad "1" smd circle
			(at 0.40005 0 180)
			(size 0 0)
			(layers "B.Cu" "B.Mask" "B.Paste")
			(net "VCCIO4")
		)
		(pad "2" smd circle
			(at -0.40005 0 180)
			(size 0 0)
			(layers "B.Cu" "B.Mask" "B.Paste")
			(net "GND")
		)
		(zone
			(layer "B.Cu")
			(hatch none 0.5)
			(connect_pads
				(clearance 0)
			)
			(min_thickness 0.25)
			(keepout
				(tracks not_allowed)
				(vias allowed)
				(pads allowed)
				(copperpour not_allowed)
				(footprints allowed)
			)
			(placement
				(enabled no)
				(sheetname "")
			)
			(fill
				(thermal_gap 0.5)
				(thermal_bridge_width 0.5)
				(island_removal_mode 0)
			)
			(polygon
				(pts
					(xy 22.843744 -93.518482) (xy 22.752304 -93.460316) (xy 22.552914 -93.460316) (xy 22.462744 -93.518482)
					(xy 22.462744 -93.693742) (xy 22.552914 -93.752162) (xy 22.752304 -93.752162) (xy 22.843744 -93.693996)
				)
			)
		)
	)
)
